(kicad_pcb
	(version 20260206)
	(generator "pcbnew")
	(generator_version "10.0")
	(general
		(thickness 1.6)
		(legacy_teardrops no)
	)
	(paper "A4")
	(title_block
		(title "Wiwynn_Tioga_Pass_MB.brd")
		(comment 1 "Tioga Pass / footprint 320 of 4770 (J1B1), pads 244-291 of 291")
	)
	(layers
		(0 "F.Cu" signal "TOP")
		(4 "In1.Cu" signal "L2GND")
		(6 "In2.Cu" signal "L3")
		(8 "In3.Cu" signal "L4GND")
		(10 "In4.Cu" signal "L5")
		(12 "In5.Cu" signal "L6GND")
		(14 "In6.Cu" signal "L7VCC")
		(16 "In7.Cu" signal "L8VCC")
		(18 "In8.Cu" signal "L9GND")
		(20 "In9.Cu" signal "L10")
		(22 "In10.Cu" signal "L11GND")
		(24 "In11.Cu" signal "L12")
		(26 "In12.Cu" signal "L13GND")
		(2 "B.Cu" signal "BOTTOM")
		(9 "F.Adhes" user "F.Adhesive")
		(11 "B.Adhes" user "B.Adhesive")
		(13 "F.Paste" user "Package Geometry/Pastemask Top")
		(15 "B.Paste" user "Package Geometry/Pastemask Bottom")
		(5 "F.SilkS" user "Ref Des/Silkscreen Top")
		(7 "B.SilkS" user "Ref Des/Silkscreen Bottom")
		(1 "F.Mask" user "Board Geometry/Soldermask Top")
		(3 "B.Mask" user "Board Geometry/Soldermask Bottom")
		(17 "Dwgs.User" user "User.Drawings")
		(19 "Cmts.User" user "User.Comments")
		(21 "Eco1.User" user "User.Eco1")
		(23 "Eco2.User" user "User.Eco2")
		(25 "Edge.Cuts" user "Board Geometry/Outline")
		(27 "Margin" user)
		(31 "F.CrtYd" user "Package Geometry/Place Bound Top")
		(29 "B.CrtYd" user "Package Geometry/Place Bound Bottom")
		(35 "F.Fab" user "Ref Des/Assembly Top")
		(33 "B.Fab" user "Ref Des/Assembly Bottom")
	)
	(footprint ""
		(layer "F.Cu")
		(at 29.699458 -133.0706 90)
		(property "Reference" "J1B1"
			(at -4.960112 38.372542 0)
			(unlocked yes)
			(layer "F.SilkS")
			(effects
				(font
					(size 0.7874 0.5842)
					(thickness 0.1524)
				)
				(justify left)
			)
		)
		(property "Value" ""
			(at 0 0 90)
			(layer "F.Fab")
			(effects
				(font
					(size 1.27 1.27)
				)
			)
		)
		(duplicate_pad_numbers_are_jumpers no)
		(pad "241" smd rect
			(at 4.59994 86.700106 90)
			(size 1.8034 0.508)
			(layers "F.Cu" "F.Mask" "F.Paste")
			(net "GND")
		)
		(pad "242" smd rect
			(at 4.59994 87.54999 90)
			(size 1.8034 0.508)
			(layers "F.Cu" "F.Mask" "F.Paste")
			(net "M_K_DQ<32>")
		)
		(pad "243" smd rect
			(at 4.59994 88.399874 90)
			(size 1.8034 0.508)
			(layers "F.Cu" "F.Mask" "F.Paste")
			(net "GND")
		)
		(pad "244" smd rect
			(at 4.59994 89.250012 90)
			(size 1.8034 0.508)
			(layers "F.Cu" "F.Mask" "F.Paste")
			(net "M_K_DQS_DN<4>")
		)
		(pad "245" smd rect
			(at 4.59994 90.099896 90)
			(size 1.8034 0.508)
			(layers "F.Cu" "F.Mask" "F.Paste")
			(net "M_K_DQS_DP<4>")
		)
		(pad "246" smd rect
			(at 4.59994 90.950034 90)
			(size 1.8034 0.508)
			(layers "F.Cu" "F.Mask" "F.Paste")
			(net "GND")
		)
		(pad "247" smd rect
			(at 4.59994 91.799918 90)
			(size 1.8034 0.508)
			(layers "F.Cu" "F.Mask" "F.Paste")
			(net "M_K_DQ<38>")
		)
		(pad "248" smd rect
			(at 4.59994 92.650056 90)
			(size 1.8034 0.508)
			(layers "F.Cu" "F.Mask" "F.Paste")
			(net "GND")
		)
		(pad "249" smd rect
			(at 4.59994 93.49994 90)
			(size 1.8034 0.508)
			(layers "F.Cu" "F.Mask" "F.Paste")
			(net "M_K_DQ<34>")
		)
		(pad "250" smd rect
			(at 4.59994 94.350078 90)
			(size 1.8034 0.508)
			(layers "F.Cu" "F.Mask" "F.Paste")
			(net "GND")
		)
		(pad "251" smd rect
			(at 4.59994 95.199962 90)
			(size 1.8034 0.508)
			(layers "F.Cu" "F.Mask" "F.Paste")
			(net "M_K_DQ<44>")
		)
		(pad "252" smd rect
			(at 4.59994 96.0501 90)
			(size 1.8034 0.508)
			(layers "F.Cu" "F.Mask" "F.Paste")
			(net "GND")
		)
		(pad "253" smd rect
			(at 4.59994 96.899984 90)
			(size 1.8034 0.508)
			(layers "F.Cu" "F.Mask" "F.Paste")
			(net "M_K_DQ<40>")
		)
		(pad "254" smd rect
			(at 4.59994 97.750122 90)
			(size 1.8034 0.508)
			(layers "F.Cu" "F.Mask" "F.Paste")
			(net "GND")
		)
		(pad "255" smd rect
			(at 4.59994 98.600006 90)
			(size 1.8034 0.508)
			(layers "F.Cu" "F.Mask" "F.Paste")
			(net "M_K_DQS_DN<5>")
		)
		(pad "256" smd rect
			(at 4.59994 99.44989 90)
			(size 1.8034 0.508)
			(layers "F.Cu" "F.Mask" "F.Paste")
			(net "M_K_DQS_DP<5>")
		)
		(pad "257" smd rect
			(at 4.59994 100.300028 90)
			(size 1.8034 0.508)
			(layers "F.Cu" "F.Mask" "F.Paste")
			(net "GND")
		)
		(pad "258" smd rect
			(at 4.59994 101.149912 90)
			(size 1.8034 0.508)
			(layers "F.Cu" "F.Mask" "F.Paste")
			(net "M_K_DQ<46>")
		)
		(pad "259" smd rect
			(at 4.59994 102.00005 90)
			(size 1.8034 0.508)
			(layers "F.Cu" "F.Mask" "F.Paste")
			(net "GND")
		)
		(pad "260" smd rect
			(at 4.59994 102.849934 90)
			(size 1.8034 0.508)
			(layers "F.Cu" "F.Mask" "F.Paste")
			(net "M_K_DQ<42>")
		)
		(pad "261" smd rect
			(at 4.59994 103.700072 90)
			(size 1.8034 0.508)
			(layers "F.Cu" "F.Mask" "F.Paste")
			(net "GND")
		)
		(pad "262" smd rect
			(at 4.59994 104.549956 90)
			(size 1.8034 0.508)
			(layers "F.Cu" "F.Mask" "F.Paste")
			(net "M_K_DQ<52>")
		)
		(pad "263" smd rect
			(at 4.59994 105.400094 90)
			(size 1.8034 0.508)
			(layers "F.Cu" "F.Mask" "F.Paste")
			(net "GND")
		)
		(pad "264" smd rect
			(at 4.59994 106.249978 90)
			(size 1.8034 0.508)
			(layers "F.Cu" "F.Mask" "F.Paste")
			(net "M_K_DQ<48>")
		)
		(pad "265" smd rect
			(at 4.59994 107.100116 90)
			(size 1.8034 0.508)
			(layers "F.Cu" "F.Mask" "F.Paste")
			(net "GND")
		)
		(pad "266" smd rect
			(at 4.59994 107.95 90)
			(size 1.8034 0.508)
			(layers "F.Cu" "F.Mask" "F.Paste")
			(net "M_K_DQS_DN<6>")
		)
		(pad "267" smd rect
			(at 4.59994 108.799884 90)
			(size 1.8034 0.508)
			(layers "F.Cu" "F.Mask" "F.Paste")
			(net "M_K_DQS_DP<6>")
		)
		(pad "268" smd rect
			(at 4.59994 109.650022 90)
			(size 1.8034 0.508)
			(layers "F.Cu" "F.Mask" "F.Paste")
			(net "GND")
		)
		(pad "269" smd rect
			(at 4.59994 110.499906 90)
			(size 1.8034 0.508)
			(layers "F.Cu" "F.Mask" "F.Paste")
			(net "M_K_DQ<54>")
		)
		(pad "270" smd rect
			(at 4.59994 111.350044 90)
			(size 1.8034 0.508)
			(layers "F.Cu" "F.Mask" "F.Paste")
			(net "GND")
		)
		(pad "271" smd rect
			(at 4.59994 112.199928 90)
			(size 1.8034 0.508)
			(layers "F.Cu" "F.Mask" "F.Paste")
			(net "M_K_DQ<50>")
		)
		(pad "272" smd rect
			(at 4.59994 113.050066 90)
			(size 1.8034 0.508)
			(layers "F.Cu" "F.Mask" "F.Paste")
			(net "GND")
		)
		(pad "273" smd rect
			(at 4.59994 113.89995 90)
			(size 1.8034 0.508)
			(layers "F.Cu" "F.Mask" "F.Paste")
			(net "M_K_DQ<60>")
		)
		(pad "274" smd rect
			(at 4.59994 114.750088 90)
			(size 1.8034 0.508)
			(layers "F.Cu" "F.Mask" "F.Paste")
			(net "GND")
		)
		(pad "275" smd rect
			(at 4.59994 115.599972 90)
			(size 1.8034 0.508)
			(layers "F.Cu" "F.Mask" "F.Paste")
			(net "M_K_DQ<56>")
		)
		(pad "276" smd rect
			(at 4.59994 116.45011 90)
			(size 1.8034 0.508)
			(layers "F.Cu" "F.Mask" "F.Paste")
			(net "GND")
		)
		(pad "277" smd rect
			(at 4.59994 117.299994 90)
			(size 1.8034 0.508)
			(layers "F.Cu" "F.Mask" "F.Paste")
			(net "M_K_DQS_DN<7>")
		)
		(pad "278" smd rect
			(at 4.59994 118.149878 90)
			(size 1.8034 0.508)
			(layers "F.Cu" "F.Mask" "F.Paste")
			(net "M_K_DQS_DP<7>")
		)
		(pad "279" smd rect
			(at 4.59994 119.000016 90)
			(size 1.8034 0.508)
			(layers "F.Cu" "F.Mask" "F.Paste")
			(net "GND")
		)
		(pad "280" smd rect
			(at 4.59994 119.8499 90)
			(size 1.8034 0.508)
			(layers "F.Cu" "F.Mask" "F.Paste")
			(net "M_K_DQ<62>")
		)
		(pad "281" smd rect
			(at 4.59994 120.700038 90)
			(size 1.8034 0.508)
			(layers "F.Cu" "F.Mask" "F.Paste")
			(net "GND")
		)
		(pad "282" smd rect
			(at 4.59994 121.549922 90)
			(size 1.8034 0.508)
			(layers "F.Cu" "F.Mask" "F.Paste")
			(net "M_K_DQ<58>")
		)
		(pad "283" smd rect
			(at 4.59994 122.40006 90)
			(size 1.8034 0.508)
			(layers "F.Cu" "F.Mask" "F.Paste")
			(net "GND")
		)
		(pad "284" smd rect
			(at 4.59994 123.249944 90)
			(size 1.8034 0.508)
			(layers "F.Cu" "F.Mask" "F.Paste")
			(net "PVPP_KLM")
		)
		(pad "285" smd rect
			(at 4.59994 124.100082 90)
			(size 1.8034 0.508)
			(layers "F.Cu" "F.Mask" "F.Paste")
			(net "SMB_DDR_KLM_VPP_SDA")
		)
		(pad "286" smd rect
			(at 4.59994 124.949966 90)
			(size 1.8034 0.508)
			(layers "F.Cu" "F.Mask" "F.Paste")
			(net "PVPP_KLM")
		)
		(pad "287" smd rect
			(at 4.59994 125.800104 90)
			(size 1.8034 0.508)
			(layers "F.Cu" "F.Mask" "F.Paste")
			(net "PVPP_KLM")
		)
		(pad "288" smd rect
			(at 4.59994 126.649988 90)
			(size 1.8034 0.508)
			(layers "F.Cu" "F.Mask" "F.Paste")
			(net "PVPP_KLM")
		)
	)
)
